FILE_TYPE = MACRO_DRAWING;
SET COLOR_WIRE YELLOW;
SET COLOR_PROP ORANGE;
SET COLOR_DOT WHITE;
SET COLOR_ARC YELLOW;
SET COLOR_BODY GREEN;
SET COLOR_NOTE PURPLE;
SET PROP_DISPLAY VALUE;
SET PAGE_NUMBER P402;
FORCEADD PT5161LRS..1
(-7675 3775);
FORCEPROP 1 LAST LOCATION U6014
J 0
(-8025 5400);
DISPLAY 0.723404 (-8025 5400);
PAINT GREEN (-8025 5400);
FORCEPROP 0 LAST $SEC 1
J 0
(-8025 5550);
DISPLAY 0.680851 (-8025 5550);
PAINT MONO (-8025 5550);
DISPLAY INVISIBLE (-8025 5550);
FORCEPROP 0 LAST CDS_SEC 1
J 0
(-8025 5550);
DISPLAY 0.680851 (-8025 5550);
DISPLAY INVISIBLE (-8025 5550);
FORCEPROP 0 LASTPIN (-7225 4925) $PN N2
J 0
(-7215 4935);
DISPLAY 0.680851 (-7215 4935);
PAINT MONO (-7215 4935);
FORCEPROP 0 LASTPIN (-7225 4575) $PN Y2
J 0
(-7215 4585);
DISPLAY 0.680851 (-7215 4585);
PAINT MONO (-7215 4585);
FORCEPROP 0 LASTPIN (-7225 4225) $PN AG2
J 0
(-7215 4235);
DISPLAY 0.680851 (-7215 4235);
PAINT MONO (-7215 4235);
FORCEPROP 0 LASTPIN (-7225 3875) $PN AP2
J 0
(-7215 3885);
DISPLAY 0.680851 (-7215 3885);
PAINT MONO (-7215 3885);
FORCEPROP 0 LASTPIN (-7225 3525) $PN BA2
J 0
(-7215 3535);
DISPLAY 0.680851 (-7215 3535);
PAINT MONO (-7215 3535);
FORCEPROP 0 LASTPIN (-7225 3175) $PN BH2
J 0
(-7215 3185);
DISPLAY 0.680851 (-7215 3185);
PAINT MONO (-7215 3185);
FORCEPROP 0 LASTPIN (-7225 2825) $PN BR2
J 0
(-7215 2835);
DISPLAY 0.680851 (-7215 2835);
PAINT MONO (-7215 2835);
FORCEPROP 0 LASTPIN (-7225 2475) $PN CB2
J 0
(-7215 2485);
DISPLAY 0.680851 (-7215 2485);
PAINT MONO (-7215 2485);
FORCEPROP 0 LASTPIN (-7225 5025) $PN R1
J 0
(-7215 5035);
DISPLAY 0.680851 (-7215 5035);
PAINT MONO (-7215 5035);
FORCEPROP 0 LASTPIN (-7225 4675) $PN AB1
J 0
(-7215 4685);
DISPLAY 0.680851 (-7215 4685);
PAINT MONO (-7215 4685);
FORCEPROP 0 LASTPIN (-7225 4325) $PN AJ1
J 0
(-7215 4335);
DISPLAY 0.680851 (-7215 4335);
PAINT MONO (-7215 4335);
FORCEPROP 0 LASTPIN (-7225 3975) $PN AT1
J 0
(-7215 3985);
DISPLAY 0.680851 (-7215 3985);
PAINT MONO (-7215 3985);
FORCEPROP 0 LASTPIN (-7225 3625) $PN BC1
J 0
(-7215 3635);
DISPLAY 0.680851 (-7215 3635);
PAINT MONO (-7215 3635);
FORCEPROP 0 LASTPIN (-7225 3275) $PN BK1
J 0
(-7215 3285);
DISPLAY 0.680851 (-7215 3285);
PAINT MONO (-7215 3285);
FORCEPROP 0 LASTPIN (-7225 2925) $PN BU1
J 0
(-7215 2935);
DISPLAY 0.680851 (-7215 2935);
PAINT MONO (-7215 2935);
FORCEPROP 0 LASTPIN (-7225 2575) $PN CD1
J 0
(-7215 2585);
DISPLAY 0.680851 (-7215 2585);
PAINT MONO (-7215 2585);
FORCEPROP 2 LAST VALUE PT5161LRS
J 0
(-8025 5450);
DISPLAY 0.680851 (-8025 5450);
FORCEPROP 1 LAST MATERIAL IC
J 0
(-8025 5250);
DISPLAY 0.723404 (-8025 5250);
PAINT GREEN (-8025 5250);
FORCEPROP 2 LAST PART_TYPE SMLF
J 0
(-8025 5500);
DISPLAY 0.680851 (-8025 5500);
FORCEPROP 1 LAST NEEDS_NO_SIZE TRUE
J 0
(-7675 3775);
DISPLAY 0.723404 (-7675 3775);
PAINT GREEN (-7675 3775);
DISPLAY INVISIBLE (-7675 3775);
FORCEPROP 1 LAST CDS_LMAN_SYM_OUTLINE -350,1450,300,-1400
J 0
(-7675 3775);
DISPLAY 0.468085 (-7675 3775);
PAINT GREEN (-7675 3775);
DISPLAY INVISIBLE (-7675 3775);
FORCEPROP 2 LAST CDS_LIB pure_quanta
J 0
(-7675 3775);
DISPLAY INVISIBLE (-7675 3775);
FORCEPROP 1 LAST PATH I1
J 0
(-7675 3775);
DISPLAY 0.723404 (-7675 3775);
PAINT GREEN (-7675 3775);
DISPLAY INVISIBLE (-7675 3775);
FORCEPROP 1 LAST PART_NUMBER AJ051610U03
J 0
(-8025 5325);
DISPLAY 0.723404 (-8025 5325);
PAINT GREEN (-8025 5325);
DISPLAY INVISIBLE (-8025 5325);
FORCEADD TAP..1
(-6450 3875);
FORCEPROP 3 LASTPIN (-6500 3875) SIG_NAME P5E_CPU1_P0_RX_BUF_DN<12>
J 0
(-6490 3885);
DISPLAY 0.659574 (-6490 3885);
PAINT MONO (-6490 3885);
DISPLAY INVISIBLE (-6490 3885);
FORCEPROP 1 LASTPIN (-6500 3875) BN 12
J 0
(-6512 3883);
DISPLAY 0.680851 (-6512 3883);
PAINT GREEN (-6512 3883);
FORCEPROP 2 LAST CDS_LIB standard
J 0
(-6450 3875);
DISPLAY INVISIBLE (-6450 3875);
FORCEPROP 1 LAST BODY_TYPE PLUMBING
J 0
(-6450 3925);
DISPLAY 0.872340 (-6450 3925);
PAINT GREEN (-6450 3925);
DISPLAY INVISIBLE (-6450 3925);
FORCEPROP 1 LAST HDL_TAP TRUE
J 0
(-6125 3750);
DISPLAY 0.872340 (-6125 3750);
DISPLAY INVISIBLE (-6125 3750);
FORCEPROP 1 LAST PATH I10
J 0
(-6452 3875);
DISPLAY 0.872340 (-6452 3875);
PAINT GREEN (-6452 3875);
DISPLAY INVISIBLE (-6452 3875);
FORCEADD TAP..1
(-6650 3975);
FORCEPROP 3 LASTPIN (-6700 3975) SIG_NAME P5E_CPU1_P0_RX_BUF_DP<12>
J 0
(-6690 3985);
DISPLAY 0.659574 (-6690 3985);
PAINT MONO (-6690 3985);
DISPLAY INVISIBLE (-6690 3985);
FORCEPROP 1 LASTPIN (-6700 3975) BN 12
J 0
(-6712 3983);
DISPLAY 0.680851 (-6712 3983);
PAINT GREEN (-6712 3983);
FORCEPROP 2 LAST CDS_LIB standard
J 0
(-6650 3975);
DISPLAY INVISIBLE (-6650 3975);
FORCEPROP 1 LAST BODY_TYPE PLUMBING
J 0
(-6650 4025);
DISPLAY 0.872340 (-6650 4025);
PAINT GREEN (-6650 4025);
DISPLAY INVISIBLE (-6650 4025);
FORCEPROP 1 LAST HDL_TAP TRUE
J 0
(-6325 3850);
DISPLAY 0.872340 (-6325 3850);
DISPLAY INVISIBLE (-6325 3850);
FORCEPROP 1 LAST PATH I11
J 0
(-6652 3975);
DISPLAY 0.872340 (-6652 3975);
PAINT GREEN (-6652 3975);
DISPLAY INVISIBLE (-6652 3975);
FORCEADD TAP..1
(-6450 4225);
FORCEPROP 3 LASTPIN (-6500 4225) SIG_NAME P5E_CPU1_P0_RX_BUF_DN<13>
J 0
(-6490 4235);
DISPLAY 0.659574 (-6490 4235);
PAINT MONO (-6490 4235);
DISPLAY INVISIBLE (-6490 4235);
FORCEPROP 1 LASTPIN (-6500 4225) BN 13
J 0
(-6512 4233);
DISPLAY 0.680851 (-6512 4233);
PAINT GREEN (-6512 4233);
FORCEPROP 2 LAST CDS_LIB standard
J 0
(-6450 4225);
DISPLAY INVISIBLE (-6450 4225);
FORCEPROP 1 LAST BODY_TYPE PLUMBING
J 0
(-6450 4275);
DISPLAY 0.872340 (-6450 4275);
PAINT GREEN (-6450 4275);
DISPLAY INVISIBLE (-6450 4275);
FORCEPROP 1 LAST HDL_TAP TRUE
J 0
(-6125 4100);
DISPLAY 0.872340 (-6125 4100);
DISPLAY INVISIBLE (-6125 4100);
FORCEPROP 1 LAST PATH I12
J 0
(-6452 4225);
DISPLAY 0.872340 (-6452 4225);
PAINT GREEN (-6452 4225);
DISPLAY INVISIBLE (-6452 4225);
FORCEADD TAP..1
(-6650 4325);
FORCEPROP 3 LASTPIN (-6700 4325) SIG_NAME P5E_CPU1_P0_RX_BUF_DP<13>
J 0
(-6690 4335);
DISPLAY 0.659574 (-6690 4335);
PAINT MONO (-6690 4335);
DISPLAY INVISIBLE (-6690 4335);
FORCEPROP 1 LASTPIN (-6700 4325) BN 13
J 0
(-6712 4333);
DISPLAY 0.680851 (-6712 4333);
PAINT GREEN (-6712 4333);
FORCEPROP 2 LAST CDS_LIB standard
J 0
(-6650 4325);
DISPLAY INVISIBLE (-6650 4325);
FORCEPROP 1 LAST BODY_TYPE PLUMBING
J 0
(-6650 4375);
DISPLAY 0.872340 (-6650 4375);
PAINT GREEN (-6650 4375);
DISPLAY INVISIBLE (-6650 4375);
FORCEPROP 1 LAST HDL_TAP TRUE
J 0
(-6325 4200);
DISPLAY 0.872340 (-6325 4200);
DISPLAY INVISIBLE (-6325 4200);
FORCEPROP 1 LAST PATH I13
J 0
(-6652 4325);
DISPLAY 0.872340 (-6652 4325);
PAINT GREEN (-6652 4325);
DISPLAY INVISIBLE (-6652 4325);
FORCEADD TAP..1
(-6450 4575);
FORCEPROP 3 LASTPIN (-6500 4575) SIG_NAME P5E_CPU1_P0_RX_BUF_DN<14>
J 0
(-6490 4585);
DISPLAY 0.659574 (-6490 4585);
PAINT MONO (-6490 4585);
DISPLAY INVISIBLE (-6490 4585);
FORCEPROP 1 LASTPIN (-6500 4575) BN 14
J 0
(-6512 4583);
DISPLAY 0.680851 (-6512 4583);
PAINT GREEN (-6512 4583);
FORCEPROP 2 LAST CDS_LIB standard
J 0
(-6450 4575);
DISPLAY INVISIBLE (-6450 4575);
FORCEPROP 1 LAST BODY_TYPE PLUMBING
J 0
(-6450 4625);
DISPLAY 0.872340 (-6450 4625);
PAINT GREEN (-6450 4625);
DISPLAY INVISIBLE (-6450 4625);
FORCEPROP 1 LAST HDL_TAP TRUE
J 0
(-6125 4450);
DISPLAY 0.872340 (-6125 4450);
DISPLAY INVISIBLE (-6125 4450);
FORCEPROP 1 LAST PATH I14
J 0
(-6452 4575);
DISPLAY 0.872340 (-6452 4575);
PAINT GREEN (-6452 4575);
DISPLAY INVISIBLE (-6452 4575);
FORCEADD TAP..1
(-6650 4675);
FORCEPROP 3 LASTPIN (-6700 4675) SIG_NAME P5E_CPU1_P0_RX_BUF_DP<14>
J 0
(-6690 4685);
DISPLAY 0.659574 (-6690 4685);
PAINT MONO (-6690 4685);
DISPLAY INVISIBLE (-6690 4685);
FORCEPROP 1 LASTPIN (-6700 4675) BN 14
J 0
(-6712 4683);
DISPLAY 0.680851 (-6712 4683);
PAINT GREEN (-6712 4683);
FORCEPROP 2 LAST CDS_LIB standard
J 0
(-6650 4675);
DISPLAY INVISIBLE (-6650 4675);
FORCEPROP 1 LAST BODY_TYPE PLUMBING
J 0
(-6650 4725);
DISPLAY 0.872340 (-6650 4725);
PAINT GREEN (-6650 4725);
DISPLAY INVISIBLE (-6650 4725);
FORCEPROP 1 LAST HDL_TAP TRUE
J 0
(-6325 4550);
DISPLAY 0.872340 (-6325 4550);
DISPLAY INVISIBLE (-6325 4550);
FORCEPROP 1 LAST PATH I15
J 0
(-6652 4675);
DISPLAY 0.872340 (-6652 4675);
PAINT GREEN (-6652 4675);
DISPLAY INVISIBLE (-6652 4675);
FORCEADD TAP..1
(-6650 5025);
FORCEPROP 3 LASTPIN (-6700 5025) SIG_NAME P5E_CPU1_P0_RX_BUF_DP<15>
J 0
(-6690 5035);
DISPLAY 0.659574 (-6690 5035);
PAINT MONO (-6690 5035);
DISPLAY INVISIBLE (-6690 5035);
FORCEPROP 1 LASTPIN (-6700 5025) BN 15
J 0
(-6712 5033);
DISPLAY 0.680851 (-6712 5033);
PAINT GREEN (-6712 5033);
FORCEPROP 2 LAST CDS_LIB standard
J 0
(-6650 5025);
DISPLAY INVISIBLE (-6650 5025);
FORCEPROP 1 LAST BODY_TYPE PLUMBING
J 0
(-6650 5075);
DISPLAY 0.872340 (-6650 5075);
PAINT GREEN (-6650 5075);
DISPLAY INVISIBLE (-6650 5075);
FORCEPROP 1 LAST HDL_TAP TRUE
J 0
(-6325 4900);
DISPLAY 0.872340 (-6325 4900);
DISPLAY INVISIBLE (-6325 4900);
FORCEPROP 1 LAST PATH I16
J 0
(-6652 5025);
DISPLAY 0.872340 (-6652 5025);
PAINT GREEN (-6652 5025);
DISPLAY INVISIBLE (-6652 5025);
FORCEADD TAP..1
(-6450 4925);
FORCEPROP 3 LASTPIN (-6500 4925) SIG_NAME P5E_CPU1_P0_RX_BUF_DN<15>
J 0
(-6490 4935);
DISPLAY 0.659574 (-6490 4935);
PAINT MONO (-6490 4935);
DISPLAY INVISIBLE (-6490 4935);
FORCEPROP 1 LASTPIN (-6500 4925) BN 15
J 0
(-6512 4933);
DISPLAY 0.680851 (-6512 4933);
PAINT GREEN (-6512 4933);
FORCEPROP 2 LAST CDS_LIB standard
J 0
(-6450 4925);
DISPLAY INVISIBLE (-6450 4925);
FORCEPROP 1 LAST BODY_TYPE PLUMBING
J 0
(-6450 4975);
DISPLAY 0.872340 (-6450 4975);
PAINT GREEN (-6450 4975);
DISPLAY INVISIBLE (-6450 4975);
FORCEPROP 1 LAST HDL_TAP TRUE
J 0
(-6125 4800);
DISPLAY 0.872340 (-6125 4800);
DISPLAY INVISIBLE (-6125 4800);
FORCEPROP 1 LAST PATH I17
J 0
(-6452 4925);
DISPLAY 0.872340 (-6452 4925);
PAINT GREEN (-6452 4925);
DISPLAY INVISIBLE (-6452 4925);
FORCEADD OFFPAGE..1
R 2
(-5425 5050);
FORCEPROP 2 LAST $XR0 121 
J 0
(-5239 5050);
DISPLAY 0.638298 (-5239 5050);
PAINT MONO (-5239 5050);
FORCEPROP 2 LAST CDS_LIB standard
J 0
(-5425 5050);
DISPLAY INVISIBLE (-5425 5050);
FORCEPROP 1 LAST OFFPAGE TRUE
J 2
(-5750 4925);
DISPLAY 0.872340 (-5750 4925);
DISPLAY INVISIBLE (-5750 4925);
FORCEPROP 1 LAST COMMENT_BODY TRUE
J 2
(-5550 4950);
DISPLAY 0.872340 (-5550 4950);
PAINT GREEN (-5550 4950);
DISPLAY INVISIBLE (-5550 4950);
FORCEPROP 2 LAST PATH I18
J 0
(-5250 5125);
DISPLAY 0.680851 (-5250 5125);
DISPLAY INVISIBLE (-5250 5125);
FORCEADD OFFPAGE..1
R 2
(-5425 5125);
FORCEPROP 2 LAST $XR0 121 
J 0
(-5239 5125);
DISPLAY 0.638298 (-5239 5125);
PAINT MONO (-5239 5125);
FORCEPROP 2 LAST CDS_LIB standard
J 0
(-5425 5125);
DISPLAY INVISIBLE (-5425 5125);
FORCEPROP 1 LAST OFFPAGE TRUE
J 2
(-5750 5000);
DISPLAY 0.872340 (-5750 5000);
DISPLAY INVISIBLE (-5750 5000);
FORCEPROP 1 LAST COMMENT_BODY TRUE
J 2
(-5550 5025);
DISPLAY 0.872340 (-5550 5025);
PAINT GREEN (-5550 5025);
DISPLAY INVISIBLE (-5550 5025);
FORCEPROP 2 LAST PATH I19
J 0
(-5250 5200);
DISPLAY 0.680851 (-5250 5200);
DISPLAY INVISIBLE (-5250 5200);
FORCEADD TAP..1
(-6650 2575);
FORCEPROP 3 LASTPIN (-6700 2575) SIG_NAME P5E_CPU1_P0_RX_BUF_DP<8>
J 0
(-6690 2585);
DISPLAY 0.659574 (-6690 2585);
PAINT MONO (-6690 2585);
DISPLAY INVISIBLE (-6690 2585);
FORCEPROP 1 LASTPIN (-6700 2575) BN 8
J 0
(-6712 2583);
DISPLAY 0.680851 (-6712 2583);
PAINT GREEN (-6712 2583);
FORCEPROP 2 LAST CDS_LIB standard
J 0
(-6650 2575);
DISPLAY INVISIBLE (-6650 2575);
FORCEPROP 1 LAST BODY_TYPE PLUMBING
J 0
(-6650 2625);
DISPLAY 0.872340 (-6650 2625);
PAINT GREEN (-6650 2625);
DISPLAY INVISIBLE (-6650 2625);
FORCEPROP 1 LAST HDL_TAP TRUE
J 0
(-6325 2450);
DISPLAY 0.872340 (-6325 2450);
DISPLAY INVISIBLE (-6325 2450);
FORCEPROP 1 LAST PATH I2
J 0
(-6652 2575);
DISPLAY 0.872340 (-6652 2575);
PAINT GREEN (-6652 2575);
DISPLAY INVISIBLE (-6652 2575);
FORCEADD TAP..1
(-2200 2600);
FORCEPROP 3 LASTPIN (-2250 2600) SIG_NAME P5E_CPU1_P0_RX_BUF_DP<0>
J 0
(-2240 2610);
DISPLAY 0.659574 (-2240 2610);
PAINT MONO (-2240 2610);
DISPLAY INVISIBLE (-2240 2610);
FORCEPROP 1 LASTPIN (-2250 2600) BN 0
J 0
(-2262 2608);
DISPLAY 0.680851 (-2262 2608);
PAINT GREEN (-2262 2608);
FORCEPROP 2 LAST CDS_LIB standard
J 0
(-2200 2600);
DISPLAY INVISIBLE (-2200 2600);
FORCEPROP 1 LAST BODY_TYPE PLUMBING
J 0
(-2200 2650);
DISPLAY 0.872340 (-2200 2650);
PAINT GREEN (-2200 2650);
DISPLAY INVISIBLE (-2200 2650);
FORCEPROP 1 LAST HDL_TAP TRUE
J 0
(-1875 2475);
DISPLAY 0.872340 (-1875 2475);
DISPLAY INVISIBLE (-1875 2475);
FORCEPROP 1 LAST PATH I20
J 0
(-2202 2600);
DISPLAY 0.872340 (-2202 2600);
PAINT GREEN (-2202 2600);
DISPLAY INVISIBLE (-2202 2600);
FORCEADD TAP..1
(-2000 2500);
FORCEPROP 3 LASTPIN (-2050 2500) SIG_NAME P5E_CPU1_P0_RX_BUF_DN<0>
J 0
(-2040 2510);
DISPLAY 0.659574 (-2040 2510);
PAINT MONO (-2040 2510);
DISPLAY INVISIBLE (-2040 2510);
FORCEPROP 1 LASTPIN (-2050 2500) BN 0
J 0
(-2062 2508);
DISPLAY 0.680851 (-2062 2508);
PAINT GREEN (-2062 2508);
FORCEPROP 2 LAST CDS_LIB standard
J 0
(-2000 2500);
DISPLAY INVISIBLE (-2000 2500);
FORCEPROP 1 LAST BODY_TYPE PLUMBING
J 0
(-2000 2550);
DISPLAY 0.872340 (-2000 2550);
PAINT GREEN (-2000 2550);
DISPLAY INVISIBLE (-2000 2550);
FORCEPROP 1 LAST HDL_TAP TRUE
J 0
(-1675 2375);
DISPLAY 0.872340 (-1675 2375);
DISPLAY INVISIBLE (-1675 2375);
FORCEPROP 1 LAST PATH I21
J 0
(-2002 2500);
DISPLAY 0.872340 (-2002 2500);
PAINT GREEN (-2002 2500);
DISPLAY INVISIBLE (-2002 2500);
FORCEADD TAP..1
(-2200 2950);
FORCEPROP 3 LASTPIN (-2250 2950) SIG_NAME P5E_CPU1_P0_RX_BUF_DP<1>
J 0
(-2240 2960);
DISPLAY 0.659574 (-2240 2960);
PAINT MONO (-2240 2960);
DISPLAY INVISIBLE (-2240 2960);
FORCEPROP 1 LASTPIN (-2250 2950) BN 1
J 0
(-2262 2958);
DISPLAY 0.680851 (-2262 2958);
PAINT GREEN (-2262 2958);
FORCEPROP 2 LAST CDS_LIB standard
J 0
(-2200 2950);
DISPLAY INVISIBLE (-2200 2950);
FORCEPROP 1 LAST BODY_TYPE PLUMBING
J 0
(-2200 3000);
DISPLAY 0.872340 (-2200 3000);
PAINT GREEN (-2200 3000);
DISPLAY INVISIBLE (-2200 3000);
FORCEPROP 1 LAST HDL_TAP TRUE
J 0
(-1875 2825);
DISPLAY 0.872340 (-1875 2825);
DISPLAY INVISIBLE (-1875 2825);
FORCEPROP 1 LAST PATH I22
J 0
(-2202 2950);
DISPLAY 0.872340 (-2202 2950);
PAINT GREEN (-2202 2950);
DISPLAY INVISIBLE (-2202 2950);
FORCEADD TAP..1
(-2200 3300);
FORCEPROP 3 LASTPIN (-2250 3300) SIG_NAME P5E_CPU1_P0_RX_BUF_DP<2>
J 0
(-2240 3310);
DISPLAY 0.659574 (-2240 3310);
PAINT MONO (-2240 3310);
DISPLAY INVISIBLE (-2240 3310);
FORCEPROP 1 LASTPIN (-2250 3300) BN 2
J 0
(-2262 3308);
DISPLAY 0.680851 (-2262 3308);
PAINT GREEN (-2262 3308);
FORCEPROP 2 LAST CDS_LIB standard
J 0
(-2200 3300);
DISPLAY INVISIBLE (-2200 3300);
FORCEPROP 1 LAST BODY_TYPE PLUMBING
J 0
(-2200 3350);
DISPLAY 0.872340 (-2200 3350);
PAINT GREEN (-2200 3350);
DISPLAY INVISIBLE (-2200 3350);
FORCEPROP 1 LAST HDL_TAP TRUE
J 0
(-1875 3175);
DISPLAY 0.872340 (-1875 3175);
DISPLAY INVISIBLE (-1875 3175);
FORCEPROP 1 LAST PATH I23
J 0
(-2202 3300);
DISPLAY 0.872340 (-2202 3300);
PAINT GREEN (-2202 3300);
DISPLAY INVISIBLE (-2202 3300);
FORCEADD TAP..1
(-2200 3650);
FORCEPROP 3 LASTPIN (-2250 3650) SIG_NAME P5E_CPU1_P0_RX_BUF_DP<3>
J 0
(-2240 3660);
DISPLAY 0.659574 (-2240 3660);
PAINT MONO (-2240 3660);
DISPLAY INVISIBLE (-2240 3660);
FORCEPROP 1 LASTPIN (-2250 3650) BN 3
J 0
(-2262 3658);
DISPLAY 0.680851 (-2262 3658);
PAINT GREEN (-2262 3658);
FORCEPROP 2 LAST CDS_LIB standard
J 0
(-2200 3650);
DISPLAY INVISIBLE (-2200 3650);
FORCEPROP 1 LAST BODY_TYPE PLUMBING
J 0
(-2200 3700);
DISPLAY 0.872340 (-2200 3700);
PAINT GREEN (-2200 3700);
DISPLAY INVISIBLE (-2200 3700);
FORCEPROP 1 LAST HDL_TAP TRUE
J 0
(-1875 3525);
DISPLAY 0.872340 (-1875 3525);
DISPLAY INVISIBLE (-1875 3525);
FORCEPROP 1 LAST PATH I24
J 0
(-2202 3650);
DISPLAY 0.872340 (-2202 3650);
PAINT GREEN (-2202 3650);
DISPLAY INVISIBLE (-2202 3650);
FORCEADD TAP..1
(-2000 3200);
FORCEPROP 3 LASTPIN (-2050 3200) SIG_NAME P5E_CPU1_P0_RX_BUF_DN<2>
J 0
(-2040 3210);
DISPLAY 0.659574 (-2040 3210);
PAINT MONO (-2040 3210);
DISPLAY INVISIBLE (-2040 3210);
FORCEPROP 1 LASTPIN (-2050 3200) BN 2
J 0
(-2062 3208);
DISPLAY 0.680851 (-2062 3208);
PAINT GREEN (-2062 3208);
FORCEPROP 2 LAST CDS_LIB standard
J 0
(-2000 3200);
DISPLAY INVISIBLE (-2000 3200);
FORCEPROP 1 LAST BODY_TYPE PLUMBING
J 0
(-2000 3250);
DISPLAY 0.872340 (-2000 3250);
PAINT GREEN (-2000 3250);
DISPLAY INVISIBLE (-2000 3250);
FORCEPROP 1 LAST HDL_TAP TRUE
J 0
(-1675 3075);
DISPLAY 0.872340 (-1675 3075);
DISPLAY INVISIBLE (-1675 3075);
FORCEPROP 1 LAST PATH I25
J 0
(-2002 3200);
DISPLAY 0.872340 (-2002 3200);
PAINT GREEN (-2002 3200);
DISPLAY INVISIBLE (-2002 3200);
FORCEADD TAP..1
(-2000 3550);
FORCEPROP 3 LASTPIN (-2050 3550) SIG_NAME P5E_CPU1_P0_RX_BUF_DN<3>
J 0
(-2040 3560);
DISPLAY 0.659574 (-2040 3560);
PAINT MONO (-2040 3560);
DISPLAY INVISIBLE (-2040 3560);
FORCEPROP 1 LASTPIN (-2050 3550) BN 3
J 0
(-2062 3558);
DISPLAY 0.680851 (-2062 3558);
PAINT GREEN (-2062 3558);
FORCEPROP 2 LAST CDS_LIB standard
J 0
(-2000 3550);
DISPLAY INVISIBLE (-2000 3550);
FORCEPROP 1 LAST BODY_TYPE PLUMBING
J 0
(-2000 3600);
DISPLAY 0.872340 (-2000 3600);
PAINT GREEN (-2000 3600);
DISPLAY INVISIBLE (-2000 3600);
FORCEPROP 1 LAST HDL_TAP TRUE
J 0
(-1675 3425);
DISPLAY 0.872340 (-1675 3425);
DISPLAY INVISIBLE (-1675 3425);
FORCEPROP 1 LAST PATH I26
J 0
(-2002 3550);
DISPLAY 0.872340 (-2002 3550);
PAINT GREEN (-2002 3550);
DISPLAY INVISIBLE (-2002 3550);
FORCEADD TAP..1
(-2200 4000);
FORCEPROP 3 LASTPIN (-2250 4000) SIG_NAME P5E_CPU1_P0_RX_BUF_DP<4>
J 0
(-2240 4010);
DISPLAY 0.659574 (-2240 4010);
PAINT MONO (-2240 4010);
DISPLAY INVISIBLE (-2240 4010);
FORCEPROP 1 LASTPIN (-2250 4000) BN 4
J 0
(-2262 4008);
DISPLAY 0.680851 (-2262 4008);
PAINT GREEN (-2262 4008);
FORCEPROP 2 LAST CDS_LIB standard
J 0
(-2200 4000);
DISPLAY INVISIBLE (-2200 4000);
FORCEPROP 1 LAST BODY_TYPE PLUMBING
J 0
(-2200 4050);
DISPLAY 0.872340 (-2200 4050);
PAINT GREEN (-2200 4050);
DISPLAY INVISIBLE (-2200 4050);
FORCEPROP 1 LAST HDL_TAP TRUE
J 0
(-1875 3875);
DISPLAY 0.872340 (-1875 3875);
DISPLAY INVISIBLE (-1875 3875);
FORCEPROP 1 LAST PATH I27
J 0
(-2202 4000);
DISPLAY 0.872340 (-2202 4000);
PAINT GREEN (-2202 4000);
DISPLAY INVISIBLE (-2202 4000);
FORCEADD TAP..1
(-2200 4350);
FORCEPROP 3 LASTPIN (-2250 4350) SIG_NAME P5E_CPU1_P0_RX_BUF_DP<5>
J 0
(-2240 4360);
DISPLAY 0.659574 (-2240 4360);
PAINT MONO (-2240 4360);
DISPLAY INVISIBLE (-2240 4360);
FORCEPROP 1 LASTPIN (-2250 4350) BN 5
J 0
(-2262 4358);
DISPLAY 0.680851 (-2262 4358);
PAINT GREEN (-2262 4358);
FORCEPROP 2 LAST CDS_LIB standard
J 0
(-2200 4350);
DISPLAY INVISIBLE (-2200 4350);
FORCEPROP 1 LAST BODY_TYPE PLUMBING
J 0
(-2200 4400);
DISPLAY 0.872340 (-2200 4400);
PAINT GREEN (-2200 4400);
DISPLAY INVISIBLE (-2200 4400);
FORCEPROP 1 LAST HDL_TAP TRUE
J 0
(-1875 4225);
DISPLAY 0.872340 (-1875 4225);
DISPLAY INVISIBLE (-1875 4225);
FORCEPROP 1 LAST PATH I28
J 0
(-2202 4350);
DISPLAY 0.872340 (-2202 4350);
PAINT GREEN (-2202 4350);
DISPLAY INVISIBLE (-2202 4350);
FORCEADD TAP..1
(-2200 4700);
FORCEPROP 3 LASTPIN (-2250 4700) SIG_NAME P5E_CPU1_P0_RX_BUF_DP<6>
J 0
(-2240 4710);
DISPLAY 0.659574 (-2240 4710);
PAINT MONO (-2240 4710);
DISPLAY INVISIBLE (-2240 4710);
FORCEPROP 1 LASTPIN (-2250 4700) BN 6
J 0
(-2262 4708);
DISPLAY 0.680851 (-2262 4708);
PAINT GREEN (-2262 4708);
FORCEPROP 2 LAST CDS_LIB standard
J 0
(-2200 4700);
DISPLAY INVISIBLE (-2200 4700);
FORCEPROP 1 LAST BODY_TYPE PLUMBING
J 0
(-2200 4750);
DISPLAY 0.872340 (-2200 4750);
PAINT GREEN (-2200 4750);
DISPLAY INVISIBLE (-2200 4750);
FORCEPROP 1 LAST HDL_TAP TRUE
J 0
(-1875 4575);
DISPLAY 0.872340 (-1875 4575);
DISPLAY INVISIBLE (-1875 4575);
FORCEPROP 1 LAST PATH I29
J 0
(-2202 4700);
DISPLAY 0.872340 (-2202 4700);
PAINT GREEN (-2202 4700);
DISPLAY INVISIBLE (-2202 4700);
FORCEADD TAP..1
(-6450 2475);
FORCEPROP 3 LASTPIN (-6500 2475) SIG_NAME P5E_CPU1_P0_RX_BUF_DN<8>
J 0
(-6490 2485);
DISPLAY 0.659574 (-6490 2485);
PAINT MONO (-6490 2485);
DISPLAY INVISIBLE (-6490 2485);
FORCEPROP 1 LASTPIN (-6500 2475) BN 8
J 0
(-6512 2483);
DISPLAY 0.680851 (-6512 2483);
PAINT GREEN (-6512 2483);
FORCEPROP 2 LAST CDS_LIB standard
J 0
(-6450 2475);
DISPLAY INVISIBLE (-6450 2475);
FORCEPROP 1 LAST BODY_TYPE PLUMBING
J 0
(-6450 2525);
DISPLAY 0.872340 (-6450 2525);
PAINT GREEN (-6450 2525);
DISPLAY INVISIBLE (-6450 2525);
FORCEPROP 1 LAST HDL_TAP TRUE
J 0
(-6125 2350);
DISPLAY 0.872340 (-6125 2350);
DISPLAY INVISIBLE (-6125 2350);
FORCEPROP 1 LAST PATH I3
J 0
(-6452 2475);
DISPLAY 0.872340 (-6452 2475);
PAINT GREEN (-6452 2475);
DISPLAY INVISIBLE (-6452 2475);
FORCEADD TAP..1
(-2000 3900);
FORCEPROP 3 LASTPIN (-2050 3900) SIG_NAME P5E_CPU1_P0_RX_BUF_DN<4>
J 0
(-2040 3910);
DISPLAY 0.659574 (-2040 3910);
PAINT MONO (-2040 3910);
DISPLAY INVISIBLE (-2040 3910);
FORCEPROP 1 LASTPIN (-2050 3900) BN 4
J 0
(-2062 3908);
DISPLAY 0.680851 (-2062 3908);
PAINT GREEN (-2062 3908);
FORCEPROP 2 LAST CDS_LIB standard
J 0
(-2000 3900);
DISPLAY INVISIBLE (-2000 3900);
FORCEPROP 1 LAST BODY_TYPE PLUMBING
J 0
(-2000 3950);
DISPLAY 0.872340 (-2000 3950);
PAINT GREEN (-2000 3950);
DISPLAY INVISIBLE (-2000 3950);
FORCEPROP 1 LAST HDL_TAP TRUE
J 0
(-1675 3775);
DISPLAY 0.872340 (-1675 3775);
DISPLAY INVISIBLE (-1675 3775);
FORCEPROP 1 LAST PATH I30
J 0
(-2002 3900);
DISPLAY 0.872340 (-2002 3900);
PAINT GREEN (-2002 3900);
DISPLAY INVISIBLE (-2002 3900);
FORCEADD TAP..1
(-2000 4250);
FORCEPROP 3 LASTPIN (-2050 4250) SIG_NAME P5E_CPU1_P0_RX_BUF_DN<5>
J 0
(-2040 4260);
DISPLAY 0.659574 (-2040 4260);
PAINT MONO (-2040 4260);
DISPLAY INVISIBLE (-2040 4260);
FORCEPROP 1 LASTPIN (-2050 4250) BN 5
J 0
(-2062 4258);
DISPLAY 0.680851 (-2062 4258);
PAINT GREEN (-2062 4258);
FORCEPROP 2 LAST CDS_LIB standard
J 0
(-2000 4250);
DISPLAY INVISIBLE (-2000 4250);
FORCEPROP 1 LAST BODY_TYPE PLUMBING
J 0
(-2000 4300);
DISPLAY 0.872340 (-2000 4300);
PAINT GREEN (-2000 4300);
DISPLAY INVISIBLE (-2000 4300);
FORCEPROP 1 LAST HDL_TAP TRUE
J 0
(-1675 4125);
DISPLAY 0.872340 (-1675 4125);
DISPLAY INVISIBLE (-1675 4125);
FORCEPROP 1 LAST PATH I31
J 0
(-2002 4250);
DISPLAY 0.872340 (-2002 4250);
PAINT GREEN (-2002 4250);
DISPLAY INVISIBLE (-2002 4250);
FORCEADD TAP..1
(-2000 4600);
FORCEPROP 3 LASTPIN (-2050 4600) SIG_NAME P5E_CPU1_P0_RX_BUF_DN<6>
J 0
(-2040 4610);
DISPLAY 0.659574 (-2040 4610);
PAINT MONO (-2040 4610);
DISPLAY INVISIBLE (-2040 4610);
FORCEPROP 1 LASTPIN (-2050 4600) BN 6
J 0
(-2062 4608);
DISPLAY 0.680851 (-2062 4608);
PAINT GREEN (-2062 4608);
FORCEPROP 2 LAST CDS_LIB standard
J 0
(-2000 4600);
DISPLAY INVISIBLE (-2000 4600);
FORCEPROP 1 LAST BODY_TYPE PLUMBING
J 0
(-2000 4650);
DISPLAY 0.872340 (-2000 4650);
PAINT GREEN (-2000 4650);
DISPLAY INVISIBLE (-2000 4650);
FORCEPROP 1 LAST HDL_TAP TRUE
J 0
(-1675 4475);
DISPLAY 0.872340 (-1675 4475);
DISPLAY INVISIBLE (-1675 4475);
FORCEPROP 1 LAST PATH I32
J 0
(-2002 4600);
DISPLAY 0.872340 (-2002 4600);
PAINT GREEN (-2002 4600);
DISPLAY INVISIBLE (-2002 4600);
FORCEADD TAP..1
(-2200 5050);
FORCEPROP 3 LASTPIN (-2250 5050) SIG_NAME P5E_CPU1_P0_RX_BUF_DP<7>
J 0
(-2240 5060);
DISPLAY 0.659574 (-2240 5060);
PAINT MONO (-2240 5060);
DISPLAY INVISIBLE (-2240 5060);
FORCEPROP 1 LASTPIN (-2250 5050) BN 7
J 0
(-2262 5058);
DISPLAY 0.680851 (-2262 5058);
PAINT GREEN (-2262 5058);
FORCEPROP 2 LAST CDS_LIB standard
J 0
(-2200 5050);
DISPLAY INVISIBLE (-2200 5050);
FORCEPROP 1 LAST BODY_TYPE PLUMBING
J 0
(-2200 5100);
DISPLAY 0.872340 (-2200 5100);
PAINT GREEN (-2200 5100);
DISPLAY INVISIBLE (-2200 5100);
FORCEPROP 1 LAST HDL_TAP TRUE
J 0
(-1875 4925);
DISPLAY 0.872340 (-1875 4925);
DISPLAY INVISIBLE (-1875 4925);
FORCEPROP 1 LAST PATH I33
J 0
(-2202 5050);
DISPLAY 0.872340 (-2202 5050);
PAINT GREEN (-2202 5050);
DISPLAY INVISIBLE (-2202 5050);
FORCEADD TAP..1
(-2000 4950);
FORCEPROP 3 LASTPIN (-2050 4950) SIG_NAME P5E_CPU1_P0_RX_BUF_DN<7>
J 0
(-2040 4960);
DISPLAY 0.659574 (-2040 4960);
PAINT MONO (-2040 4960);
DISPLAY INVISIBLE (-2040 4960);
FORCEPROP 1 LASTPIN (-2050 4950) BN 7
J 0
(-2062 4958);
DISPLAY 0.680851 (-2062 4958);
PAINT GREEN (-2062 4958);
FORCEPROP 2 LAST CDS_LIB standard
J 0
(-2000 4950);
DISPLAY INVISIBLE (-2000 4950);
FORCEPROP 1 LAST BODY_TYPE PLUMBING
J 0
(-2000 5000);
DISPLAY 0.872340 (-2000 5000);
PAINT GREEN (-2000 5000);
DISPLAY INVISIBLE (-2000 5000);
FORCEPROP 1 LAST HDL_TAP TRUE
J 0
(-1675 4825);
DISPLAY 0.872340 (-1675 4825);
DISPLAY INVISIBLE (-1675 4825);
FORCEPROP 1 LAST PATH I34
J 0
(-2002 4950);
DISPLAY 0.872340 (-2002 4950);
PAINT GREEN (-2002 4950);
DISPLAY INVISIBLE (-2002 4950);
FORCEADD OFFPAGE..1
R 2
(-975 5075);
FORCEPROP 2 LAST $XR0 122 
J 0
(-789 5075);
DISPLAY 0.638298 (-789 5075);
PAINT MONO (-789 5075);
FORCEPROP 2 LAST CDS_LIB standard
J 0
(-975 5075);
DISPLAY INVISIBLE (-975 5075);
FORCEPROP 1 LAST OFFPAGE TRUE
J 2
(-1300 4950);
DISPLAY 0.872340 (-1300 4950);
DISPLAY INVISIBLE (-1300 4950);
FORCEPROP 1 LAST COMMENT_BODY TRUE
J 2
(-1100 4975);
DISPLAY 0.872340 (-1100 4975);
PAINT GREEN (-1100 4975);
DISPLAY INVISIBLE (-1100 4975);
FORCEPROP 2 LAST PATH I35
J 0
(-800 5150);
DISPLAY 0.680851 (-800 5150);
DISPLAY INVISIBLE (-800 5150);
FORCEADD OFFPAGE..1
R 2
(-975 5150);
FORCEPROP 2 LAST $XR0 122 
J 0
(-789 5150);
DISPLAY 0.638298 (-789 5150);
PAINT MONO (-789 5150);
FORCEPROP 2 LAST CDS_LIB standard
J 0
(-975 5150);
DISPLAY INVISIBLE (-975 5150);
FORCEPROP 1 LAST OFFPAGE TRUE
J 2
(-1300 5025);
DISPLAY 0.872340 (-1300 5025);
DISPLAY INVISIBLE (-1300 5025);
FORCEPROP 1 LAST COMMENT_BODY TRUE
J 2
(-1100 5050);
DISPLAY 0.872340 (-1100 5050);
PAINT GREEN (-1100 5050);
DISPLAY INVISIBLE (-1100 5050);
FORCEPROP 2 LAST PATH I36
J 0
(-800 5225);
DISPLAY 0.680851 (-800 5225);
DISPLAY INVISIBLE (-800 5225);
FORCEADD TAP..1
(-2000 2850);
FORCEPROP 3 LASTPIN (-2050 2850) SIG_NAME P5E_CPU1_P0_RX_BUF_DN<1>
J 0
(-2040 2860);
DISPLAY 0.659574 (-2040 2860);
PAINT MONO (-2040 2860);
DISPLAY INVISIBLE (-2040 2860);
FORCEPROP 1 LASTPIN (-2050 2850) BN 1
J 0
(-2062 2858);
DISPLAY 0.680851 (-2062 2858);
PAINT GREEN (-2062 2858);
FORCEPROP 2 LAST CDS_LIB standard
J 0
(-2000 2850);
DISPLAY INVISIBLE (-2000 2850);
FORCEPROP 1 LAST BODY_TYPE PLUMBING
J 0
(-2000 2900);
DISPLAY 0.872340 (-2000 2900);
PAINT GREEN (-2000 2900);
DISPLAY INVISIBLE (-2000 2900);
FORCEPROP 1 LAST HDL_TAP TRUE
J 0
(-1675 2725);
DISPLAY 0.872340 (-1675 2725);
DISPLAY INVISIBLE (-1675 2725);
FORCEPROP 1 LAST PATH I37
J 0
(-2002 2850);
DISPLAY 0.872340 (-2002 2850);
PAINT GREEN (-2002 2850);
DISPLAY INVISIBLE (-2002 2850);
FORCEADD PT5161LRS..2
(-3225 3800);
FORCEPROP 1 LAST LOCATION U6014
J 0
(-3575 5425);
DISPLAY 0.723404 (-3575 5425);
PAINT GREEN (-3575 5425);
FORCEPROP 0 LAST $SEC 2
J 0
(-3575 5575);
DISPLAY 0.680851 (-3575 5575);
PAINT MONO (-3575 5575);
DISPLAY INVISIBLE (-3575 5575);
FORCEPROP 0 LAST CDS_SEC 2
J 0
(-3575 5575);
DISPLAY 0.680851 (-3575 5575);
DISPLAY INVISIBLE (-3575 5575);
FORCEPROP 0 LASTPIN (-2775 4950) $PN CJ2
J 0
(-2765 4960);
DISPLAY 0.680851 (-2765 4960);
PAINT MONO (-2765 4960);
FORCEPROP 0 LASTPIN (-2775 4600) $PN CT2
J 0
(-2765 4610);
DISPLAY 0.680851 (-2765 4610);
PAINT MONO (-2765 4610);
FORCEPROP 0 LASTPIN (-2775 4250) $PN DC2
J 0
(-2765 4260);
DISPLAY 0.680851 (-2765 4260);
PAINT MONO (-2765 4260);
FORCEPROP 0 LASTPIN (-2775 3900) $PN DK2
J 0
(-2765 3910);
DISPLAY 0.680851 (-2765 3910);
PAINT MONO (-2765 3910);
FORCEPROP 0 LASTPIN (-2775 3550) $PN DU2
J 0
(-2765 3560);
DISPLAY 0.680851 (-2765 3560);
PAINT MONO (-2765 3560);
FORCEPROP 0 LASTPIN (-2775 3200) $PN ED2
J 0
(-2765 3210);
DISPLAY 0.680851 (-2765 3210);
PAINT MONO (-2765 3210);
FORCEPROP 0 LASTPIN (-2775 2850) $PN EL2
J 0
(-2765 2860);
DISPLAY 0.680851 (-2765 2860);
PAINT MONO (-2765 2860);
FORCEPROP 0 LASTPIN (-2775 2500) $PN EV2
J 0
(-2765 2510);
DISPLAY 0.680851 (-2765 2510);
PAINT MONO (-2765 2510);
FORCEPROP 0 LASTPIN (-2775 5050) $PN CL1
J 0
(-2765 5060);
DISPLAY 0.680851 (-2765 5060);
PAINT MONO (-2765 5060);
FORCEPROP 0 LASTPIN (-2775 4700) $PN CV1
J 0
(-2765 4710);
DISPLAY 0.680851 (-2765 4710);
PAINT MONO (-2765 4710);
FORCEPROP 0 LASTPIN (-2775 4350) $PN DE1
J 0
(-2765 4360);
DISPLAY 0.680851 (-2765 4360);
PAINT MONO (-2765 4360);
FORCEPROP 0 LASTPIN (-2775 4000) $PN DM1
J 0
(-2765 4010);
DISPLAY 0.680851 (-2765 4010);
PAINT MONO (-2765 4010);
FORCEPROP 0 LASTPIN (-2775 3650) $PN DW1
J 0
(-2765 3660);
DISPLAY 0.680851 (-2765 3660);
PAINT MONO (-2765 3660);
FORCEPROP 0 LASTPIN (-2775 3300) $PN EF1
J 0
(-2765 3310);
DISPLAY 0.680851 (-2765 3310);
PAINT MONO (-2765 3310);
FORCEPROP 0 LASTPIN (-2775 2950) $PN EN1
J 0
(-2765 2960);
DISPLAY 0.680851 (-2765 2960);
PAINT MONO (-2765 2960);
FORCEPROP 0 LASTPIN (-2775 2600) $PN EY1
J 0
(-2765 2610);
DISPLAY 0.680851 (-2765 2610);
PAINT MONO (-2765 2610);
FORCEPROP 2 LAST PART_TYPE SMLF
J 0
(-3575 5525);
DISPLAY 0.680851 (-3575 5525);
FORCEPROP 1 LAST MATERIAL IC
J 0
(-3575 5275);
DISPLAY 0.723404 (-3575 5275);
PAINT GREEN (-3575 5275);
FORCEPROP 2 LAST VALUE PT5161LRS
J 0
(-3575 5475);
DISPLAY 0.680851 (-3575 5475);
FORCEPROP 2 LAST CDS_LIB pure_quanta
J 0
(-3225 3800);
DISPLAY INVISIBLE (-3225 3800);
FORCEPROP 1 LAST CDS_LMAN_SYM_OUTLINE -350,1450,300,-1400
J 0
(-3225 3800);
DISPLAY 0.468085 (-3225 3800);
PAINT GREEN (-3225 3800);
DISPLAY INVISIBLE (-3225 3800);
FORCEPROP 1 LAST NEEDS_NO_SIZE TRUE
J 0
(-3225 3800);
DISPLAY 0.723404 (-3225 3800);
PAINT GREEN (-3225 3800);
DISPLAY INVISIBLE (-3225 3800);
FORCEPROP 1 LAST PATH I38
J 0
(-3225 3800);
DISPLAY 0.723404 (-3225 3800);
PAINT GREEN (-3225 3800);
DISPLAY INVISIBLE (-3225 3800);
FORCEPROP 1 LAST PART_NUMBER AJ051610U03
J 0
(-3575 5350);
DISPLAY 0.723404 (-3575 5350);
PAINT GREEN (-3575 5350);
DISPLAY INVISIBLE (-3575 5350);
FORCEADD TAP..1
(-6650 2925);
FORCEPROP 3 LASTPIN (-6700 2925) SIG_NAME P5E_CPU1_P0_RX_BUF_DP<9>
J 0
(-6690 2935);
DISPLAY 0.659574 (-6690 2935);
PAINT MONO (-6690 2935);
DISPLAY INVISIBLE (-6690 2935);
FORCEPROP 1 LASTPIN (-6700 2925) BN 9
J 0
(-6712 2933);
DISPLAY 0.680851 (-6712 2933);
PAINT GREEN (-6712 2933);
FORCEPROP 2 LAST CDS_LIB standard
J 0
(-6650 2925);
DISPLAY INVISIBLE (-6650 2925);
FORCEPROP 1 LAST BODY_TYPE PLUMBING
J 0
(-6650 2975);
DISPLAY 0.872340 (-6650 2975);
PAINT GREEN (-6650 2975);
DISPLAY INVISIBLE (-6650 2975);
FORCEPROP 1 LAST HDL_TAP TRUE
J 0
(-6325 2800);
DISPLAY 0.872340 (-6325 2800);
DISPLAY INVISIBLE (-6325 2800);
FORCEPROP 1 LAST PATH I4
J 0
(-6652 2925);
DISPLAY 0.872340 (-6652 2925);
PAINT GREEN (-6652 2925);
DISPLAY INVISIBLE (-6652 2925);
FORCEADD TAP..1
(-6450 2825);
FORCEPROP 3 LASTPIN (-6500 2825) SIG_NAME P5E_CPU1_P0_RX_BUF_DN<9>
J 0
(-6490 2835);
DISPLAY 0.659574 (-6490 2835);
PAINT MONO (-6490 2835);
DISPLAY INVISIBLE (-6490 2835);
FORCEPROP 1 LASTPIN (-6500 2825) BN 9
J 0
(-6512 2833);
DISPLAY 0.680851 (-6512 2833);
PAINT GREEN (-6512 2833);
FORCEPROP 2 LAST CDS_LIB standard
J 0
(-6450 2825);
DISPLAY INVISIBLE (-6450 2825);
FORCEPROP 1 LAST BODY_TYPE PLUMBING
J 0
(-6450 2875);
DISPLAY 0.872340 (-6450 2875);
PAINT GREEN (-6450 2875);
DISPLAY INVISIBLE (-6450 2875);
FORCEPROP 1 LAST HDL_TAP TRUE
J 0
(-6125 2700);
DISPLAY 0.872340 (-6125 2700);
DISPLAY INVISIBLE (-6125 2700);
FORCEPROP 1 LAST PATH I5
J 0
(-6452 2825);
DISPLAY 0.872340 (-6452 2825);
PAINT GREEN (-6452 2825);
DISPLAY INVISIBLE (-6452 2825);
FORCEADD TAP..1
(-6650 3275);
FORCEPROP 3 LASTPIN (-6700 3275) SIG_NAME P5E_CPU1_P0_RX_BUF_DP<10>
J 0
(-6690 3285);
DISPLAY 0.659574 (-6690 3285);
PAINT MONO (-6690 3285);
DISPLAY INVISIBLE (-6690 3285);
FORCEPROP 1 LASTPIN (-6700 3275) BN 10
J 0
(-6712 3283);
DISPLAY 0.680851 (-6712 3283);
PAINT GREEN (-6712 3283);
FORCEPROP 2 LAST CDS_LIB standard
J 0
(-6650 3275);
DISPLAY INVISIBLE (-6650 3275);
FORCEPROP 1 LAST BODY_TYPE PLUMBING
J 0
(-6650 3325);
DISPLAY 0.872340 (-6650 3325);
PAINT GREEN (-6650 3325);
DISPLAY INVISIBLE (-6650 3325);
FORCEPROP 1 LAST HDL_TAP TRUE
J 0
(-6325 3150);
DISPLAY 0.872340 (-6325 3150);
DISPLAY INVISIBLE (-6325 3150);
FORCEPROP 1 LAST PATH I6
J 0
(-6652 3275);
DISPLAY 0.872340 (-6652 3275);
PAINT GREEN (-6652 3275);
DISPLAY INVISIBLE (-6652 3275);
FORCEADD TAP..1
(-6450 3175);
FORCEPROP 3 LASTPIN (-6500 3175) SIG_NAME P5E_CPU1_P0_RX_BUF_DN<10>
J 0
(-6490 3185);
DISPLAY 0.659574 (-6490 3185);
PAINT MONO (-6490 3185);
DISPLAY INVISIBLE (-6490 3185);
FORCEPROP 1 LASTPIN (-6500 3175) BN 10
J 0
(-6512 3183);
DISPLAY 0.680851 (-6512 3183);
PAINT GREEN (-6512 3183);
FORCEPROP 2 LAST CDS_LIB standard
J 0
(-6450 3175);
DISPLAY INVISIBLE (-6450 3175);
FORCEPROP 1 LAST BODY_TYPE PLUMBING
J 0
(-6450 3225);
DISPLAY 0.872340 (-6450 3225);
PAINT GREEN (-6450 3225);
DISPLAY INVISIBLE (-6450 3225);
FORCEPROP 1 LAST HDL_TAP TRUE
J 0
(-6125 3050);
DISPLAY 0.872340 (-6125 3050);
DISPLAY INVISIBLE (-6125 3050);
FORCEPROP 1 LAST PATH I7
J 0
(-6452 3175);
DISPLAY 0.872340 (-6452 3175);
PAINT GREEN (-6452 3175);
DISPLAY INVISIBLE (-6452 3175);
FORCEADD TAP..1
(-6450 3525);
FORCEPROP 3 LASTPIN (-6500 3525) SIG_NAME P5E_CPU1_P0_RX_BUF_DN<11>
J 0
(-6490 3535);
DISPLAY 0.659574 (-6490 3535);
PAINT MONO (-6490 3535);
DISPLAY INVISIBLE (-6490 3535);
FORCEPROP 1 LASTPIN (-6500 3525) BN 11
J 0
(-6512 3533);
DISPLAY 0.680851 (-6512 3533);
PAINT GREEN (-6512 3533);
FORCEPROP 2 LAST CDS_LIB standard
J 0
(-6450 3525);
DISPLAY INVISIBLE (-6450 3525);
FORCEPROP 1 LAST BODY_TYPE PLUMBING
J 0
(-6450 3575);
DISPLAY 0.872340 (-6450 3575);
PAINT GREEN (-6450 3575);
DISPLAY INVISIBLE (-6450 3575);
FORCEPROP 1 LAST HDL_TAP TRUE
J 0
(-6125 3400);
DISPLAY 0.872340 (-6125 3400);
DISPLAY INVISIBLE (-6125 3400);
FORCEPROP 1 LAST PATH I8
J 0
(-6452 3525);
DISPLAY 0.872340 (-6452 3525);
PAINT GREEN (-6452 3525);
DISPLAY INVISIBLE (-6452 3525);
FORCEADD TAP..1
(-6650 3625);
FORCEPROP 3 LASTPIN (-6700 3625) SIG_NAME P5E_CPU1_P0_RX_BUF_DP<11>
J 0
(-6690 3635);
DISPLAY 0.659574 (-6690 3635);
PAINT MONO (-6690 3635);
DISPLAY INVISIBLE (-6690 3635);
FORCEPROP 1 LASTPIN (-6700 3625) BN 11
J 0
(-6712 3633);
DISPLAY 0.680851 (-6712 3633);
PAINT GREEN (-6712 3633);
FORCEPROP 2 LAST CDS_LIB standard
J 0
(-6650 3625);
DISPLAY INVISIBLE (-6650 3625);
FORCEPROP 1 LAST BODY_TYPE PLUMBING
J 0
(-6650 3675);
DISPLAY 0.872340 (-6650 3675);
PAINT GREEN (-6650 3675);
DISPLAY INVISIBLE (-6650 3675);
FORCEPROP 1 LAST HDL_TAP TRUE
J 0
(-6325 3500);
DISPLAY 0.872340 (-6325 3500);
DISPLAY INVISIBLE (-6325 3500);
FORCEPROP 1 LAST PATH I9
J 0
(-6652 3625);
DISPLAY 0.872340 (-6652 3625);
PAINT GREEN (-6652 3625);
DISPLAY INVISIBLE (-6652 3625);
FORCEADD QUANTA_TITLE_BLOCK_C..1
(0 0);
FORCEPROP 0 LAST CDS_CON_LAST_MODIFIED Thu Sep 14 16:12:51 2023
J 0
(-1885 15);
DISPLAY INVISIBLE (-1885 15);
FORCEPROP 1 LAST CUSTOM_TXT_CDS <CON_LAST_MODIFIED>
J 0
(-1885 15);
DISPLAY 0.978723 (-1885 15);
FORCEPROP 2 LAST CUSTOM_TXT_CDS <XR_PAGE_TITLE>
J 0
(-7890 5250);
DISPLAY 0.638298 (-7890 5250);
PAINT PINK (-7890 5250);
DISPLAY INVISIBLE (-7890 5250);
FORCEPROP 1 LAST CUSTOM_TXT_CDS <NAME_2>
J 0
(-3175 50);
FORCEPROP 1 LAST CUSTOM_TXT_CDS <NAME_1>
J 0
(-3175 175);
FORCEPROP 1 LAST CUSTOM_TXT_CDS <Q_NUMBER>
J 0
(-1403 103);
DISPLAY 1.212766 (-1403 103);
FORCEPROP 1 LAST CUSTOM_TXT_CDS <Q_PROJ>
J 0
(-2382 102);
DISPLAY 1.212766 (-2382 102);
FORCEPROP 1 LAST CUSTOM_TXT_CDS <Q_REV>
J 0
(-184 103);
DISPLAY 1.212766 (-184 103);
FORCEPROP 1 LAST CUSTOM_TXT_CDS <CON_PAGE_NUM> OF <CON_TOTAL_PAGES>
J 0
(-446 18);
DISPLAY 0.978723 (-446 18);
FORCEPROP 1 LAST Q_TITLE RETIMER_CPU1_P0(3)
J 0
(-9366 26);
DISPLAY 2.446809 (-9366 26);
PAINT GREEN (-9366 26);
FORCEPROP 2 LAST CDS_LIB pure_quanta
J 0
(0 0);
DISPLAY INVISIBLE (0 0);
FORCEPROP 1 LAST CDS_LMAN_SYM_OUTLINE -9475,6775,100,-125
J 0
(0 0);
DISPLAY 0.468085 (0 0);
PAINT GREEN (0 0);
DISPLAY INVISIBLE (0 0);
FORCEPROP 2 LAST PAGE_BORDER TRUE
J 0
(-7890 5250);
DISPLAY 0.638298 (-7890 5250);
PAINT PINK (-7890 5250);
DISPLAY INVISIBLE (-7890 5250);
FORCEPROP 2 LAST CDS_XR_PAGE_TITLE CR-319 : @T6G_MB_LIB.T6G(SCH_1):PAGE319
J 0
(-7890 5250);
DISPLAY 0.638298 (-7890 5250);
PAINT PINK (-7890 5250);
DISPLAY INVISIBLE (-7890 5250);
FORCEPROP 1 LAST Q_DEPT BU9
J 1
(-3763 49);
DISPLAY 1.957447 (-3763 49);
PAINT GREEN (-3763 49);
DISPLAY INVISIBLE (-3763 49);
FORCEPROP 1 LAST COMMENT_BODY TRUE
J 0
(12 -13);
DISPLAY 0.978723 (12 -13);
PAINT GREEN (12 -13);
DISPLAY INVISIBLE (12 -13);
WIRE 17 -1 (-2150 5150)(-2150 5075);
WIRE 17 -1 (-2150 5150)(-1025 5150);
FORCEPROP 2 LAST SIG_NAME P5E_CPU1_P0_RX_BUF_DP<7:0>
J 0
(-1885 5160);
DISPLAY 0.680851 (-1885 5160);
PAINT WHITE (-1885 5160);
WIRE 17 -1 (-1950 4975)(-1950 4625);
WIRE 17 -1 (-1950 5075)(-1950 4975);
WIRE 17 -1 (-1950 4625)(-1950 4275);
WIRE 17 -1 (-1950 4275)(-1950 3925);
WIRE 17 -1 (-1950 5075)(-1025 5075);
FORCEPROP 2 LAST SIG_NAME P5E_CPU1_P0_RX_BUF_DN<7:0>
J 0
(-1885 5085);
DISPLAY 0.680851 (-1885 5085);
PAINT WHITE (-1885 5085);
WIRE 17 -1 (-2150 4725)(-2150 4375);
WIRE 17 -1 (-2150 5075)(-2150 4725);
WIRE 17 -1 (-2150 4375)(-2150 4025);
WIRE 17 -1 (-2150 3675)(-2150 4025);
WIRE 17 -1 (-1950 3575)(-1950 3925);
WIRE 17 -1 (-1950 2875)(-1950 2525);
WIRE 17 -1 (-1950 3225)(-1950 2875);
WIRE 17 -1 (-1950 3575)(-1950 3225);
WIRE 17 -1 (-2150 2975)(-2150 2625);
WIRE 17 -1 (-2150 3325)(-2150 2975);
WIRE 17 -1 (-2150 3675)(-2150 3325);
WIRE 17 -1 (-6600 5125)(-6600 5050);
WIRE 17 -1 (-6600 5125)(-5475 5125);
FORCEPROP 2 LAST SIG_NAME P5E_CPU1_P0_RX_BUF_DP<15:8>
J 0
(-6335 5135);
DISPLAY 0.680851 (-6335 5135);
PAINT WHITE (-6335 5135);
WIRE 17 -1 (-6400 5050)(-6400 4950);
WIRE 17 -1 (-6400 5050)(-5475 5050);
FORCEPROP 2 LAST SIG_NAME P5E_CPU1_P0_RX_BUF_DN<15:8>
J 0
(-6335 5060);
DISPLAY 0.680851 (-6335 5060);
PAINT WHITE (-6335 5060);
WIRE 17 -1 (-6400 4950)(-6400 4600);
WIRE 17 -1 (-6400 4600)(-6400 4250);
WIRE 17 -1 (-6400 4250)(-6400 3900);
WIRE 17 -1 (-6400 3550)(-6400 3900);
WIRE 17 -1 (-6400 3550)(-6400 3200);
WIRE 17 -1 (-6400 3200)(-6400 2850);
WIRE 17 -1 (-6400 2850)(-6400 2500);
WIRE 17 -1 (-6600 2950)(-6600 2600);
WIRE 17 -1 (-6600 3300)(-6600 2950);
WIRE 17 -1 (-6600 3650)(-6600 3300);
WIRE 17 -1 (-6600 3650)(-6600 4000);
WIRE 17 -1 (-6600 4350)(-6600 4000);
WIRE 17 -1 (-6600 4700)(-6600 4350);
WIRE 17 -1 (-6600 5050)(-6600 4700);
WIRE 16 -1 (-7225 3625)(-6700 3625);
WIRE 16 -1 (-7225 3275)(-6700 3275);
WIRE 16 -1 (-7225 2925)(-6700 2925);
WIRE 16 -1 (-7225 2475)(-6500 2475);
WIRE 16 -1 (-7225 3525)(-6500 3525);
WIRE 16 -1 (-7225 3175)(-6500 3175);
WIRE 16 -1 (-7225 4675)(-6700 4675);
WIRE 16 -1 (-2775 2950)(-2250 2950);
WIRE 16 -1 (-2775 3650)(-2250 3650);
WIRE 16 -1 (-2775 4000)(-2250 4000);
WIRE 16 -1 (-2775 4700)(-2250 4700);
WIRE 16 -1 (-2775 3900)(-2050 3900);
WIRE 16 -1 (-2775 3200)(-2050 3200);
WIRE 16 -1 (-2775 3300)(-2250 3300);
WIRE 16 -1 (-7225 4225)(-6500 4225);
WIRE 16 -1 (-7225 4325)(-6700 4325);
WIRE 16 -1 (-7225 3975)(-6700 3975);
WIRE 16 -1 (-7225 2575)(-6700 2575);
WIRE 16 -1 (-7225 2825)(-6500 2825);
WIRE 16 -1 (-7225 3875)(-6500 3875);
WIRE 16 -1 (-7225 4575)(-6500 4575);
WIRE 16 -1 (-7225 4925)(-6500 4925);
WIRE 16 -1 (-7225 5025)(-6700 5025);
WIRE 16 -1 (-2775 4950)(-2050 4950);
WIRE 16 -1 (-2775 2600)(-2250 2600);
WIRE 16 -1 (-2775 2850)(-2050 2850);
WIRE 16 -1 (-2775 3550)(-2050 3550);
WIRE 16 -1 (-2775 2500)(-2050 2500);
WIRE 16 -1 (-2775 4250)(-2050 4250);
WIRE 16 -1 (-2775 4350)(-2250 4350);
WIRE 16 -1 (-2775 4600)(-2050 4600);
WIRE 16 -1 (-2775 5050)(-2250 5050);
FORCENOTE
P5E_CPU1_P0_RX_BUF_DP/DN<0-15> LANE REVERSAL
(-9100 6350) 0;
DISPLAY LEFT (-9100 6350);
DISPLAY 2.000000 (-9100 6350);
FORCENOTE
EXAMAX TO RETIMER
(-8050 1650) 0;
DISPLAY LEFT (-8050 1650);
DISPLAY 3.148936 (-8050 1650);
FORCENOTE
EXAMAX TO RETIMER
(-3500 1625) 0;
DISPLAY LEFT (-3500 1625);
DISPLAY 3.148936 (-3500 1625);
QUIT
